(kicad_pcb
	(version 20260206)
	(generator "pcbnew")
	(generator_version "10.0")
	(general
		(thickness 1.6)
		(legacy_teardrops no)
	)
	(paper "A4")
	(title_block
		(title "01162023_DA0F0TEBIF0_F0T_Expander_BD_F_brd_V02_OCP.brd")
		(comment 1 "Grand Teton / footprints 700-704 of 9728")
	)
	(layers
		(0 "F.Cu" signal "TOP")
		(4 "In1.Cu" signal "GND")
		(6 "In2.Cu" signal "VCC")
		(8 "In3.Cu" signal "VCC1")
		(10 "In4.Cu" signal "GND1")
		(12 "In5.Cu" signal "IN1")
		(14 "In6.Cu" signal "GND2")
		(16 "In7.Cu" signal "IN2")
		(18 "In8.Cu" signal "GND3")
		(20 "In9.Cu" signal "IN3")
		(22 "In10.Cu" signal "GND4")
		(24 "In11.Cu" signal "IN4")
		(26 "In12.Cu" signal "GND5")
		(28 "In13.Cu" signal "IN5")
		(30 "In14.Cu" signal "GND6")
		(32 "In15.Cu" signal "IN6")
		(34 "In16.Cu" signal "GND7")
		(2 "B.Cu" signal "BOTTOM")
		(9 "F.Adhes" user "F.Adhesive")
		(11 "B.Adhes" user "B.Adhesive")
		(13 "F.Paste" user "Package Geometry/Pastemask Top")
		(15 "B.Paste" user "Package Geometry/Pastemask Bottom")
		(5 "F.SilkS" user "Ref Des/Silkscreen Top")
		(7 "B.SilkS" user "Ref Des/Silkscreen Bottom")
		(1 "F.Mask" user "Board Geometry/Soldermask Top")
		(3 "B.Mask" user "Board Geometry/Soldermask Bottom")
		(17 "Dwgs.User" user "User.Drawings")
		(19 "Cmts.User" user "User.Comments")
		(21 "Eco1.User" user "User.Eco1")
		(23 "Eco2.User" user "User.Eco2")
		(25 "Edge.Cuts" user "Board Geometry/Outline")
		(27 "Margin" user)
		(31 "F.CrtYd" user "Package Geometry/Place Bound Top")
		(29 "B.CrtYd" user "Package Geometry/Place Bound Bottom")
		(35 "F.Fab" user "Ref Des/Assembly Top")
		(33 "B.Fab" user "Ref Des/Assembly Bottom")
	)
	(footprint ""
		(layer "F.Cu")
		(at 386.70738 -343.952322 90)
		(property "Reference" "C792"
			(at 0 0 90)
			(layer "F.SilkS")
			(hide yes)
			(effects
				(font
					(size 1.27 1.27)
				)
			)
		)
		(property "Value" ""
			(at 0 0 90)
			(layer "F.Fab")
			(effects
				(font
					(size 1.27 1.27)
				)
			)
		)
		(duplicate_pad_numbers_are_jumpers no)
		(fp_line
			(start 0.299974 -0.150114)
			(end 0.299974 0.150114)
			(stroke
				(width 0.1)
				(type default)
			)
			(layer "F.Fab")
		)
		(fp_line
			(start -0.299974 -0.150114)
			(end 0.299974 -0.150114)
			(stroke
				(width 0.1)
				(type default)
			)
			(layer "F.Fab")
		)
		(fp_line
			(start 0.299974 0.150114)
			(end -0.299974 0.150114)
			(stroke
				(width 0.1)
				(type default)
			)
			(layer "F.Fab")
		)
		(fp_line
			(start -0.299974 0.150114)
			(end -0.299974 -0.150114)
			(stroke
				(width 0.1)
				(type default)
			)
			(layer "F.Fab")
		)
		(pad "1" smd rect
			(at -0.2667 0 90)
			(size 0.3048 0.381)
			(layers "F.Cu" "F.Mask" "F.Paste")
			(net "P5E_PEX3_STN6_TX_DP<96>")
		)
		(pad "2" smd rect
			(at 0.2667 0 90)
			(size 0.3048 0.381)
			(layers "F.Cu" "F.Mask" "F.Paste")
			(net "P5E_PEX3_STN6_TX_C_DP<96>")
		)
	)
	(footprint ""
		(layer "F.Cu")
		(at 361.188 -177.038 180)
		(property "Reference" "R4707"
			(at 0 0 180)
			(layer "F.SilkS")
			(hide yes)
			(effects
				(font
					(size 1.27 1.27)
				)
			)
		)
		(property "Value" ""
			(at 0 0 180)
			(layer "F.Fab")
			(effects
				(font
					(size 1.27 1.27)
				)
			)
		)
		(duplicate_pad_numbers_are_jumpers no)
		(fp_line
			(start 0.7874 0.4064)
			(end -0.7874 0.4064)
			(stroke
				(width 0.1524)
				(type default)
			)
			(layer "F.SilkS")
		)
		(fp_line
			(start 0.7874 -0.4064)
			(end 0.7874 0.4064)
			(stroke
				(width 0.1524)
				(type default)
			)
			(layer "F.SilkS")
		)
		(fp_line
			(start -0.7874 0.4064)
			(end -0.7874 -0.4064)
			(stroke
				(width 0.1524)
				(type default)
			)
			(layer "F.SilkS")
		)
		(fp_line
			(start -0.7874 -0.4064)
			(end 0.7874 -0.4064)
			(stroke
				(width 0.1524)
				(type default)
			)
			(layer "F.SilkS")
		)
		(fp_line
			(start 0.67945 0.3048)
			(end 0.120396 0.3048)
			(stroke
				(width 0.1)
				(type default)
			)
			(layer "F.Fab")
		)
		(fp_line
			(start 0.67945 -0.3048)
			(end 0.67945 0.3048)
			(stroke
				(width 0.1)
				(type default)
			)
			(layer "F.Fab")
		)
		(fp_line
			(start 0.12065 -0.2794)
			(end 0.12065 -0.3048)
			(stroke
				(width 0.1)
				(type default)
			)
			(layer "F.Fab")
		)
		(fp_line
			(start 0.12065 -0.3048)
			(end 0.67945 -0.3048)
			(stroke
				(width 0.1)
				(type default)
			)
			(layer "F.Fab")
		)
		(fp_line
			(start 0.120396 0.3048)
			(end 0.120396 0.2794)
			(stroke
				(width 0.1)
				(type default)
			)
			(layer "F.Fab")
		)
		(fp_line
			(start 0.120396 0.2794)
			(end -0.12065 0.2794)
			(stroke
				(width 0.1)
				(type default)
			)
			(layer "F.Fab")
		)
		(fp_line
			(start -0.12065 0.3048)
			(end -0.67945 0.3048)
			(stroke
				(width 0.1)
				(type default)
			)
			(layer "F.Fab")
		)
		(fp_line
			(start -0.12065 0.2794)
			(end -0.12065 0.3048)
			(stroke
				(width 0.1)
				(type default)
			)
			(layer "F.Fab")
		)
		(fp_line
			(start -0.12065 -0.2794)
			(end 0.12065 -0.2794)
			(stroke
				(width 0.1)
				(type default)
			)
			(layer "F.Fab")
		)
		(fp_line
			(start -0.12065 -0.305054)
			(end -0.12065 -0.2794)
			(stroke
				(width 0.1)
				(type default)
			)
			(layer "F.Fab")
		)
		(fp_line
			(start -0.67945 0.3048)
			(end -0.67945 -0.305054)
			(stroke
				(width 0.1)
				(type default)
			)
			(layer "F.Fab")
		)
		(fp_line
			(start -0.67945 -0.305054)
			(end -0.12065 -0.305054)
			(stroke
				(width 0.1)
				(type default)
			)
			(layer "F.Fab")
		)
		(pad "1" smd circle
			(at -0.40005 0 180)
			(size 0 0)
			(layers "F.Cu" "F.Mask" "F.Paste")
			(net "RST_PEX_SSD6_PERST_N")
		)
		(pad "2" smd circle
			(at 0.40005 0 180)
			(size 0 0)
			(layers "F.Cu" "F.Mask" "F.Paste")
			(net "RST_PEX_SSD6_PERST_R_N")
		)
	)
	(footprint ""
		(layer "F.Cu")
		(at 239.86871 -156.288994 -90)
		(property "Reference" "PR7024"
			(at 0 0 270)
			(layer "F.SilkS")
			(hide yes)
			(effects
				(font
					(size 1.27 1.27)
				)
			)
		)
		(property "Value" ""
			(at 0 0 270)
			(layer "F.Fab")
			(effects
				(font
					(size 1.27 1.27)
				)
			)
		)
		(duplicate_pad_numbers_are_jumpers no)
		(fp_line
			(start -0.7874 0.4064)
			(end -0.7874 -0.4064)
			(stroke
				(width 0.1524)
				(type default)
			)
			(layer "F.SilkS")
		)
		(fp_line
			(start 0.7874 0.4064)
			(end -0.7874 0.4064)
			(stroke
				(width 0.1524)
				(type default)
			)
			(layer "F.SilkS")
		)
		(fp_line
			(start -0.7874 -0.4064)
			(end 0.7874 -0.4064)
			(stroke
				(width 0.1524)
				(type default)
			)
			(layer "F.SilkS")
		)
		(fp_line
			(start 0.7874 -0.4064)
			(end 0.7874 0.4064)
			(stroke
				(width 0.1524)
				(type default)
			)
			(layer "F.SilkS")
		)
		(fp_line
			(start -0.67945 0.3048)
			(end -0.67945 -0.305054)
			(stroke
				(width 0.1)
				(type default)
			)
			(layer "F.Fab")
		)
		(fp_line
			(start -0.12065 0.3048)
			(end -0.67945 0.3048)
			(stroke
				(width 0.1)
				(type default)
			)
			(layer "F.Fab")
		)
		(fp_line
			(start 0.120396 0.3048)
			(end 0.120396 0.2794)
			(stroke
				(width 0.1)
				(type default)
			)
			(layer "F.Fab")
		)
		(fp_line
			(start 0.67945 0.3048)
			(end 0.120396 0.3048)
			(stroke
				(width 0.1)
				(type default)
			)
			(layer "F.Fab")
		)
		(fp_line
			(start -0.12065 0.2794)
			(end -0.12065 0.3048)
			(stroke
				(width 0.1)
				(type default)
			)
			(layer "F.Fab")
		)
		(fp_line
			(start 0.120396 0.2794)
			(end -0.12065 0.2794)
			(stroke
				(width 0.1)
				(type default)
			)
			(layer "F.Fab")
		)
		(fp_line
			(start -0.12065 -0.2794)
			(end 0.12065 -0.2794)
			(stroke
				(width 0.1)
				(type default)
			)
			(layer "F.Fab")
		)
		(fp_line
			(start 0.12065 -0.2794)
			(end 0.12065 -0.3048)
			(stroke
				(width 0.1)
				(type default)
			)
			(layer "F.Fab")
		)
		(fp_line
			(start 0.12065 -0.3048)
			(end 0.67945 -0.3048)
			(stroke
				(width 0.1)
				(type default)
			)
			(layer "F.Fab")
		)
		(fp_line
			(start 0.67945 -0.3048)
			(end 0.67945 0.3048)
			(stroke
				(width 0.1)
				(type default)
			)
			(layer "F.Fab")
		)
		(fp_line
			(start -0.67945 -0.305054)
			(end -0.12065 -0.305054)
			(stroke
				(width 0.1)
				(type default)
			)
			(layer "F.Fab")
		)
		(fp_line
			(start -0.12065 -0.305054)
			(end -0.12065 -0.2794)
			(stroke
				(width 0.1)
				(type default)
			)
			(layer "F.Fab")
		)
		(pad "1" smd circle
			(at -0.40005 0 270)
			(size 0 0)
			(layers "F.Cu" "F.Mask" "F.Paste")
			(net "P12V_NIC4_CO_OV_FB")
		)
		(pad "2" smd circle
			(at 0.40005 0 270)
			(size 0 0)
			(layers "F.Cu" "F.Mask" "F.Paste")
			(net "P12V_AUX")
		)
	)
	(footprint ""
		(layer "F.Cu")
		(at 336.467704 -53.051456)
		(property "Reference" "R4472"
			(at 0 0 0)
			(layer "F.SilkS")
			(hide yes)
			(effects
				(font
					(size 1.27 1.27)
				)
			)
		)
		(property "Value" ""
			(at 0 0 0)
			(layer "F.Fab")
			(effects
				(font
					(size 1.27 1.27)
				)
			)
		)
		(duplicate_pad_numbers_are_jumpers no)
		(fp_line
			(start -0.7874 -0.4064)
			(end 0.7874 -0.4064)
			(stroke
				(width 0.1524)
				(type default)
			)
			(layer "F.SilkS")
		)
		(fp_line
			(start -0.7874 0.4064)
			(end -0.7874 -0.4064)
			(stroke
				(width 0.1524)
				(type default)
			)
			(layer "F.SilkS")
		)
		(fp_line
			(start 0.7874 -0.4064)
			(end 0.7874 0.4064)
			(stroke
				(width 0.1524)
				(type default)
			)
			(layer "F.SilkS")
		)
		(fp_line
			(start 0.7874 0.4064)
			(end -0.7874 0.4064)
			(stroke
				(width 0.1524)
				(type default)
			)
			(layer "F.SilkS")
		)
		(fp_line
			(start -0.67945 -0.305054)
			(end -0.12065 -0.305054)
			(stroke
				(width 0.1)
				(type default)
			)
			(layer "F.Fab")
		)
		(fp_line
			(start -0.67945 0.3048)
			(end -0.67945 -0.305054)
			(stroke
				(width 0.1)
				(type default)
			)
			(layer "F.Fab")
		)
		(fp_line
			(start -0.12065 -0.305054)
			(end -0.12065 -0.2794)
			(stroke
				(width 0.1)
				(type default)
			)
			(layer "F.Fab")
		)
		(fp_line
			(start -0.12065 -0.2794)
			(end 0.12065 -0.2794)
			(stroke
				(width 0.1)
				(type default)
			)
			(layer "F.Fab")
		)
		(fp_line
			(start -0.12065 0.2794)
			(end -0.12065 0.3048)
			(stroke
				(width 0.1)
				(type default)
			)
			(layer "F.Fab")
		)
		(fp_line
			(start -0.12065 0.3048)
			(end -0.67945 0.3048)
			(stroke
				(width 0.1)
				(type default)
			)
			(layer "F.Fab")
		)
		(fp_line
			(start 0.120396 0.2794)
			(end -0.12065 0.2794)
			(stroke
				(width 0.1)
				(type default)
			)
			(layer "F.Fab")
		)
		(fp_line
			(start 0.120396 0.3048)
			(end 0.120396 0.2794)
			(stroke
				(width 0.1)
				(type default)
			)
			(layer "F.Fab")
		)
		(fp_line
			(start 0.12065 -0.3048)
			(end 0.67945 -0.3048)
			(stroke
				(width 0.1)
				(type default)
			)
			(layer "F.Fab")
		)
		(fp_line
			(start 0.12065 -0.2794)
			(end 0.12065 -0.3048)
			(stroke
				(width 0.1)
				(type default)
			)
			(layer "F.Fab")
		)
		(fp_line
			(start 0.67945 -0.3048)
			(end 0.67945 0.3048)
			(stroke
				(width 0.1)
				(type default)
			)
			(layer "F.Fab")
		)
		(fp_line
			(start 0.67945 0.3048)
			(end 0.120396 0.3048)
			(stroke
				(width 0.1)
				(type default)
			)
			(layer "F.Fab")
		)
		(pad "1" smd circle
			(at -0.40005 0)
			(size 0 0)
			(layers "F.Cu" "F.Mask" "F.Paste")
			(net "PWRGD_P12V_SSD11")
		)
		(pad "2" smd circle
			(at 0.40005 0)
			(size 0 0)
			(layers "F.Cu" "F.Mask" "F.Paste")
			(net "PWRGD_P12V_SSD11_R")
		)
	)
	(footprint ""
		(layer "F.Cu")
		(at 245.29796 -352.400108 180)
		(property "Reference" "J69"
			(at -0.43815 -8.612886 0)
			(unlocked yes)
			(layer "F.SilkS")
			(effects
				(font
					(size 0.7874 0.5842)
					(thickness 0.1524)
				)
				(justify left)
			)
		)
		(property "Value" ""
			(at 0 0 180)
			(layer "F.Fab")
			(effects
				(font
					(size 1.27 1.27)
				)
			)
		)
		(duplicate_pad_numbers_are_jumpers no)
		(fp_line
			(start 2.500122 7.649972)
			(end -2.500122 7.649972)
			(stroke
				(width 0.1524)
				(type default)
			)
			(layer "F.SilkS")
		)
		(fp_line
			(start 2.500122 7.559802)
			(end 2.500122 7.649972)
			(stroke
				(width 0.1524)
				(type default)
			)
			(layer "F.SilkS")
		)
		(fp_line
			(start 2.500122 5.44449)
			(end 2.500122 5.880354)
			(stroke
				(width 0.1524)
				(type default)
			)
			(layer "F.SilkS")
		)
		(fp_line
			(start 2.500122 -5.880354)
			(end 2.500122 -5.44449)
			(stroke
				(width 0.1524)
				(type default)
			)
			(layer "F.SilkS")
		)
		(fp_line
			(start 2.500122 -7.649972)
			(end 2.500122 -7.559802)
			(stroke
				(width 0.1524)
				(type default)
			)
			(layer "F.SilkS")
		)
		(fp_line
			(start -2.500122 7.649972)
			(end -2.500122 7.559802)
			(stroke
				(width 0.1524)
				(type default)
			)
			(layer "F.SilkS")
		)
		(fp_line
			(start -2.500122 5.880354)
			(end -2.500122 4.944618)
			(stroke
				(width 0.1524)
				(type default)
			)
			(layer "F.SilkS")
		)
		(fp_line
			(start -2.500122 -4.944618)
			(end -2.500122 -5.880354)
			(stroke
				(width 0.1524)
				(type default)
			)
			(layer "F.SilkS")
		)
		(fp_line
			(start -2.500122 -7.559802)
			(end -2.500122 -7.649972)
			(stroke
				(width 0.1524)
				(type default)
			)
			(layer "F.SilkS")
		)
		(fp_line
			(start -2.500122 -7.649972)
			(end 2.500122 -7.649972)
			(stroke
				(width 0.1524)
				(type default)
			)
			(layer "F.SilkS")
		)
		(fp_poly
			(pts
				(xy 4.133088 -4.49199) (xy 4.133088 -5.50799) (xy 3.117088 -4.99999)
			)
			(stroke
				(width 0)
				(type default)
			)
			(fill yes)
			(layer "F.SilkS")
		)
		(fp_line
			(start 2.500122 7.649972)
			(end -2.500122 7.649972)
			(stroke
				(width 0.1)
				(type default)
			)
			(layer "F.Fab")
		)
		(fp_line
			(start 2.500122 -7.649972)
			(end 2.500122 7.649972)
			(stroke
				(width 0.1)
				(type default)
			)
			(layer "F.Fab")
		)
		(fp_line
			(start -2.500122 7.649972)
			(end -2.500122 -7.649972)
			(stroke
				(width 0.1)
				(type default)
			)
			(layer "F.Fab")
		)
		(fp_line
			(start -2.500122 -7.649972)
			(end 2.500122 -7.649972)
			(stroke
				(width 0.1)
				(type default)
			)
			(layer "F.Fab")
		)
		(fp_poly
			(pts
				(xy 4.133088 -4.49199) (xy 4.133088 -5.50799) (xy 3.117088 -4.99999)
			)
			(stroke
				(width 0)
				(type default)
			)
			(fill yes)
			(layer "F.Fab")
		)
		(pad "" np_thru_hole circle
			(at -1.100074 -5.5245 90)
			(size 0.762 0.762)
			(drill 0.762)
			(layers "*.Cu" "*.Mask")
			(clearance 0.381)
			(thermal_gap 0.381)
		)
		(pad "" np_thru_hole circle
			(at -1.100074 5.5245 90)
			(size 0.762 0.762)
			(drill 0.762)
			(layers "*.Cu" "*.Mask")
			(clearance 0.381)
			(thermal_gap 0.381)
		)
		(pad "1" smd rect
			(at 1.720088 -4.99999 90)
			(size 0.6096 2.413)
			(layers "F.Cu" "F.Mask" "F.Paste")
			(net "GND")
		)
		(pad "2" smd rect
			(at 1.720088 -3.999992 90)
			(size 0.6096 2.413)
			(layers "F.Cu" "F.Mask" "F.Paste")
			(net "P12V_AUX")
		)
		(pad "3" smd rect
			(at 1.720088 -2.999994 90)
			(size 0.6096 2.413)
			(layers "F.Cu" "F.Mask" "F.Paste")
			(net "P12V_HSC_GATE2")
		)
		(pad "4" smd rect
			(at 1.720088 -1.999996 90)
			(size 0.6096 2.413)
			(layers "F.Cu" "F.Mask" "F.Paste")
			(net "P12V_HSC_GATE1")
		)
		(pad "5" smd rect
			(at 1.720088 -0.999998 90)
			(size 0.6096 2.413)
			(layers "F.Cu" "F.Mask" "F.Paste")
			(net "P12V_HSC_ADC_P")
		)
		(pad "6" smd rect
			(at 1.720088 0 90)
			(size 0.6096 2.413)
			(layers "F.Cu" "F.Mask" "F.Paste")
			(net "P12V_HSC_ADC_N")
		)
		(pad "7" smd rect
			(at 1.720088 0.999998 90)
			(size 0.6096 2.413)
			(layers "F.Cu" "F.Mask" "F.Paste")
			(net "P12V_HSC_SENSE2_N")
		)
		(pad "8" smd rect
			(at 1.720088 1.999996 90)
			(size 0.6096 2.413)
			(layers "F.Cu" "F.Mask" "F.Paste")
			(net "P12V_HSC_SENSE2_P")
		)
		(pad "9" smd rect
			(at 1.720088 2.999994 90)
			(size 0.6096 2.413)
			(layers "F.Cu" "F.Mask" "F.Paste")
			(net "P12V_HSC_SENSE1_N")
		)
		(pad "10" smd rect
			(at 1.720088 3.999992 90)
			(size 0.6096 2.413)
			(layers "F.Cu" "F.Mask" "F.Paste")
			(net "P12V_HSC_SENSE1_P")
		)
		(pad "11" smd rect
			(at 1.720088 4.99999 90)
			(size 0.6096 2.413)
			(layers "F.Cu" "F.Mask" "F.Paste")
			(net "P12V_STBY")
		)
		(pad "12" smd rect
			(at -1.720088 -4.500118 270)
			(size 0.6096 2.413)
			(layers "F.Cu" "F.Mask" "F.Paste")
			(net "GND")
		)
		(pad "13" smd rect
			(at -1.720088 -3.50012 270)
			(size 0.6096 2.413)
			(layers "F.Cu" "F.Mask" "F.Paste")
			(net "IRQ_SML1_PMBUS_ALERT_N")
		)
		(pad "14" smd rect
			(at -1.720088 -2.500122 270)
			(size 0.6096 2.413)
			(layers "F.Cu" "F.Mask" "F.Paste")
			(net "SMB_SML1_PMBUS_HSC_SDA")
		)
		(pad "15" smd rect
			(at -1.720088 -1.500124 270)
			(size 0.6096 2.413)
			(layers "F.Cu" "F.Mask" "F.Paste")
			(net "SMB_SML1_PMBUS_HSC_SCL")
		)
		(pad "16" smd rect
			(at -1.720088 -0.499872 270)
			(size 0.6096 2.413)
			(layers "F.Cu" "F.Mask" "F.Paste")
			(net "HSC_TYPE_ADC")
		)
		(pad "17" smd rect
			(at -1.720088 0.499872 270)
			(size 0.6096 2.413)
			(layers "F.Cu" "F.Mask" "F.Paste")
			(net "HSC_CSOUT")
		)
		(pad "18" smd rect
			(at -1.720088 1.500124 270)
			(size 0.6096 2.413)
			(layers "F.Cu" "F.Mask" "F.Paste")
			(net "MB0_P12V_STBY_PWRGD")
		)
		(pad "19" smd rect
			(at -1.720088 2.500122 270)
			(size 0.6096 2.413)
			(layers "F.Cu" "F.Mask" "F.Paste")
			(net "P12V_HSC_EN")
		)
		(pad "20" smd rect
			(at -1.720088 3.50012 270)
			(size 0.6096 2.413)
			(layers "F.Cu" "F.Mask" "F.Paste")
			(net "IRQ_HSC_FAULT_R_N")
		)
		(pad "21" smd rect
			(at -1.720088 4.500118 270)
			(size 0.6096 2.413)
			(layers "F.Cu" "F.Mask" "F.Paste")
			(net "P3V3_AUX")
		)
		(pad "G1" smd circle
			(at 0 -6.720078 270)
			(size 0 0)
			(layers "F.Cu" "F.Mask" "F.Paste")
			(net "GND")
		)
		(pad "G2" smd circle
			(at 0 6.720078 270)
			(size 0 0)
			(layers "F.Cu" "F.Mask" "F.Paste")
			(net "GND")
		)
		(zone
			(layer "F.Cu")
			(hatch none 0.5)
			(connect_pads
				(clearance 0)
			)
			(min_thickness 0.25)
			(keepout
				(tracks not_allowed)
				(vias allowed)
				(pads allowed)
				(copperpour not_allowed)
				(footprints allowed)
			)
			(placement
				(enabled no)
				(sheetname "")
			)
			(fill
				(thermal_gap 0.5)
				(thermal_bridge_width 0.5)
				(island_removal_mode 0)
			)
			(polygon
				(pts
					(xy 244.835172 -357.704898) (xy 244.835172 -347.095318) (xy 245.760748 -347.095318) (xy 245.760748 -357.704898)
				)
			)
		)
		(zone
			(layers "F.Cu" "B.Cu" "In1.Cu" "In2.Cu" "In3.Cu" "In4.Cu" "In5.Cu" "In6.Cu"
				"In7.Cu" "In8.Cu" "In9.Cu" "In10.Cu" "In11.Cu" "In12.Cu" "In13.Cu" "In14.Cu"
				"In15.Cu" "In16.Cu"
			)
			(hatch none 0.5)
			(connect_pads
				(clearance 0)
			)
			(min_thickness 0.25)
			(keepout
				(tracks not_allowed)
				(vias allowed)
				(pads allowed)
				(copperpour not_allowed)
				(footprints allowed)
			)
			(placement
				(enabled no)
				(sheetname "")
			)
			(fill
				(thermal_gap 0.5)
				(thermal_bridge_width 0.5)
				(island_removal_mode 0)
			)
			(polygon
				(pts
					(arc
						(start 247.28678 -357.924608)
						(mid 245.509288 -357.924608)
						(end 247.28678 -357.924608)
					)
				)
			)
		)
		(zone
			(layers "F.Cu" "B.Cu" "In1.Cu" "In2.Cu" "In3.Cu" "In4.Cu" "In5.Cu" "In6.Cu"
				"In7.Cu" "In8.Cu" "In9.Cu" "In10.Cu" "In11.Cu" "In12.Cu" "In13.Cu" "In14.Cu"
				"In15.Cu" "In16.Cu"
			)
			(hatch none 0.5)
			(connect_pads
				(clearance 0)
			)
			(min_thickness 0.25)
			(keepout
				(tracks not_allowed)
				(vias allowed)
				(pads allowed)
				(copperpour not_allowed)
				(footprints allowed)
			)
			(placement
				(enabled no)
				(sheetname "")
			)
			(fill
				(thermal_gap 0.5)
				(thermal_bridge_width 0.5)
				(island_removal_mode 0)
			)
			(polygon
				(pts
					(arc
						(start 247.28678 -346.875608)
						(mid 245.509288 -346.875608)
						(end 247.28678 -346.875608)
					)
				)
			)
		)
	)
)
